# S9S_MB_2U (Grand Teton) — schematic netlist excerpt (pin names and nets, part order shuffled) for the footprints in the layout excerpt that follows; sources: Cadence DE-HDL packaged netlist, KiCad conversion of 03242023_DA0F0TMBIJ0_F0T_Motherboard_J_brd_V01_OCP.brd

C769  Q_CAP_DIFFBUS  DIFF BUS_0.22UF 6.3V 20% X6S  pkg C0201  page 176 : \1\ = P5E_CPU1_PE2_TX_C_DP<2> ; \2\ = P5E_CPU1_PE2_TX_DP<2>
PC561_P1_1  Q_CAP  3300PF 50V 10% X7R  pkg 0402  page 285 : A = SW_P12V_PVCCIN_CPU1_FLT ; B = GND
R4714  Q_RES  33.2 1% CHIP  pkg 0402LF  page 213 : A = SMB_HOST_3V3AUX_SDA_R4 ; B = SMB_HOST_3V3AUX_PLD_SDA

(kicad_pcb
	(version 20260206)
	(generator "pcbnew")
	(generator_version "10.0")
	(general
		(thickness 1.6)
		(legacy_teardrops no)
	)
	(paper "A4")
	(title_block
		(title "03242023_DA0F0TMBIJ0_F0T_Motherboard_J_brd_V01_OCP.brd")
		(comment 1 "Grand Teton / footprints 631-633 of 6105")
	)
	(layers
		(0 "F.Cu" signal "TOP")
		(4 "In1.Cu" signal "GND")
		(6 "In2.Cu" signal "IN1")
		(8 "In3.Cu" signal "GND1")
		(10 "In4.Cu" signal "IN2")
		(12 "In5.Cu" signal "GND2")
		(14 "In6.Cu" signal "IN3")
		(16 "In7.Cu" signal "GND3")
		(18 "In8.Cu" signal "VCC")
		(20 "In9.Cu" signal "VCC1")
		(22 "In10.Cu" signal "GND4")
		(24 "In11.Cu" signal "IN4")
		(26 "In12.Cu" signal "GND5")
		(28 "In13.Cu" signal "IN5")
		(30 "In14.Cu" signal "GND6")
		(32 "In15.Cu" signal "IN6")
		(34 "In16.Cu" signal "GND7")
		(2 "B.Cu" signal "BOTTOM")
		(9 "F.Adhes" user "F.Adhesive")
		(11 "B.Adhes" user "B.Adhesive")
		(13 "F.Paste" user "Package Geometry/Pastemask Top")
		(15 "B.Paste" user "Package Geometry/Pastemask Bottom")
		(5 "F.SilkS" user "Ref Des/Silkscreen Top")
		(7 "B.SilkS" user "Ref Des/Silkscreen Bottom")
		(1 "F.Mask" user "Board Geometry/Soldermask Top")
		(3 "B.Mask" user "Board Geometry/Soldermask Bottom")
		(17 "Dwgs.User" user "User.Drawings")
		(19 "Cmts.User" user "User.Comments")
		(21 "Eco1.User" user "User.Eco1")
		(23 "Eco2.User" user "User.Eco2")
		(25 "Edge.Cuts" user "Board Geometry/Outline")
		(27 "Margin" user)
		(31 "F.CrtYd" user "Package Geometry/Place Bound Top")
		(29 "B.CrtYd" user "Package Geometry/Place Bound Bottom")
		(35 "F.Fab" user "Ref Des/Assembly Top")
		(33 "B.Fab" user "Ref Des/Assembly Bottom")
	)
	(footprint ""
		(layer "F.Cu")
		(at 243.045234 -137.344658)
		(property "Reference" "R4714"
			(at 0 0 0)
			(layer "F.SilkS")
			(hide yes)
			(effects
				(font
					(size 1.27 1.27)
				)
			)
		)
		(property "Value" ""
			(at 0 0 0)
			(layer "F.Fab")
			(effects
				(font
					(size 1.27 1.27)
				)
			)
		)
		(duplicate_pad_numbers_are_jumpers no)
		(fp_line
			(start -0.7874 -0.4064)
			(end 0.7874 -0.4064)
			(stroke
				(width 0.1524)
				(type default)
			)
			(layer "F.SilkS")
		)
		(fp_line
			(start -0.7874 0.4064)
			(end -0.7874 -0.4064)
			(stroke
				(width 0.1524)
				(type default)
			)
			(layer "F.SilkS")
		)
		(fp_line
			(start 0.7874 -0.4064)
			(end 0.7874 0.4064)
			(stroke
				(width 0.1524)
				(type default)
			)
			(layer "F.SilkS")
		)
		(fp_line
			(start 0.7874 0.4064)
			(end -0.7874 0.4064)
			(stroke
				(width 0.1524)
				(type default)
			)
			(layer "F.SilkS")
		)
		(fp_line
			(start -0.67945 -0.305054)
			(end -0.12065 -0.305054)
			(stroke
				(width 0.1)
				(type default)
			)
			(layer "F.Fab")
		)
		(fp_line
			(start -0.67945 0.3048)
			(end -0.67945 -0.305054)
			(stroke
				(width 0.1)
				(type default)
			)
			(layer "F.Fab")
		)
		(fp_line
			(start -0.12065 -0.305054)
			(end -0.12065 -0.2794)
			(stroke
				(width 0.1)
				(type default)
			)
			(layer "F.Fab")
		)
		(fp_line
			(start -0.12065 -0.2794)
			(end 0.12065 -0.2794)
			(stroke
				(width 0.1)
				(type default)
			)
			(layer "F.Fab")
		)
		(fp_line
			(start -0.12065 0.2794)
			(end -0.12065 0.3048)
			(stroke
				(width 0.1)
				(type default)
			)
			(layer "F.Fab")
		)
		(fp_line
			(start -0.12065 0.3048)
			(end -0.67945 0.3048)
			(stroke
				(width 0.1)
				(type default)
			)
			(layer "F.Fab")
		)
		(fp_line
			(start 0.120396 0.2794)
			(end -0.12065 0.2794)
			(stroke
				(width 0.1)
				(type default)
			)
			(layer "F.Fab")
		)
		(fp_line
			(start 0.120396 0.3048)
			(end 0.120396 0.2794)
			(stroke
				(width 0.1)
				(type default)
			)
			(layer "F.Fab")
		)
		(fp_line
			(start 0.12065 -0.3048)
			(end 0.67945 -0.3048)
			(stroke
				(width 0.1)
				(type default)
			)
			(layer "F.Fab")
		)
		(fp_line
			(start 0.12065 -0.2794)
			(end 0.12065 -0.3048)
			(stroke
				(width 0.1)
				(type default)
			)
			(layer "F.Fab")
		)
		(fp_line
			(start 0.67945 -0.3048)
			(end 0.67945 0.3048)
			(stroke
				(width 0.1)
				(type default)
			)
			(layer "F.Fab")
		)
		(fp_line
			(start 0.67945 0.3048)
			(end 0.120396 0.3048)
			(stroke
				(width 0.1)
				(type default)
			)
			(layer "F.Fab")
		)
		(pad "1" smd circle
			(at -0.40005 0)
			(size 0 0)
			(layers "F.Cu" "F.Mask" "F.Paste")
			(net "SMB_HOST_3V3AUX_SDA_R4")
		)
		(pad "2" smd circle
			(at 0.40005 0)
			(size 0 0)
			(layers "F.Cu" "F.Mask" "F.Paste")
			(net "SMB_HOST_3V3AUX_PLD_SDA")
		)
	)
	(footprint ""
		(layer "F.Cu")
		(at 100.989384 -337.856068)
		(property "Reference" "PC561_P1_1"
			(at 0 0 0)
			(layer "F.SilkS")
			(hide yes)
			(effects
				(font
					(size 1.27 1.27)
				)
			)
		)
		(property "Value" ""
			(at 0 0 0)
			(layer "F.Fab")
			(effects
				(font
					(size 1.27 1.27)
				)
			)
		)
		(duplicate_pad_numbers_are_jumpers no)
		(fp_line
			(start -0.7874 -0.4064)
			(end 0.7874 -0.4064)
			(stroke
				(width 0.1524)
				(type default)
			)
			(layer "F.SilkS")
		)
		(fp_line
			(start -0.7874 0.4064)
			(end -0.7874 -0.4064)
			(stroke
				(width 0.1524)
				(type default)
			)
			(layer "F.SilkS")
		)
		(fp_line
			(start 0.7874 -0.4064)
			(end 0.7874 0.4064)
			(stroke
				(width 0.1524)
				(type default)
			)
			(layer "F.SilkS")
		)
		(fp_line
			(start 0.7874 0.4064)
			(end -0.7874 0.4064)
			(stroke
				(width 0.1524)
				(type default)
			)
			(layer "F.SilkS")
		)
		(fp_line
			(start -0.67945 -0.305054)
			(end -0.12065 -0.305054)
			(stroke
				(width 0.1)
				(type default)
			)
			(layer "F.Fab")
		)
		(fp_line
			(start -0.67945 0.3048)
			(end -0.67945 -0.305054)
			(stroke
				(width 0.1)
				(type default)
			)
			(layer "F.Fab")
		)
		(fp_line
			(start -0.12065 -0.305054)
			(end -0.12065 -0.2794)
			(stroke
				(width 0.1)
				(type default)
			)
			(layer "F.Fab")
		)
		(fp_line
			(start -0.12065 -0.2794)
			(end 0.12065 -0.2794)
			(stroke
				(width 0.1)
				(type default)
			)
			(layer "F.Fab")
		)
		(fp_line
			(start -0.12065 0.2794)
			(end -0.12065 0.3048)
			(stroke
				(width 0.1)
				(type default)
			)
			(layer "F.Fab")
		)
		(fp_line
			(start -0.12065 0.3048)
			(end -0.67945 0.3048)
			(stroke
				(width 0.1)
				(type default)
			)
			(layer "F.Fab")
		)
		(fp_line
			(start 0.120396 0.2794)
			(end -0.12065 0.2794)
			(stroke
				(width 0.1)
				(type default)
			)
			(layer "F.Fab")
		)
		(fp_line
			(start 0.120396 0.3048)
			(end 0.120396 0.2794)
			(stroke
				(width 0.1)
				(type default)
			)
			(layer "F.Fab")
		)
		(fp_line
			(start 0.12065 -0.3048)
			(end 0.67945 -0.3048)
			(stroke
				(width 0.1)
				(type default)
			)
			(layer "F.Fab")
		)
		(fp_line
			(start 0.12065 -0.2794)
			(end 0.12065 -0.3048)
			(stroke
				(width 0.1)
				(type default)
			)
			(layer "F.Fab")
		)
		(fp_line
			(start 0.67945 -0.3048)
			(end 0.67945 0.3048)
			(stroke
				(width 0.1)
				(type default)
			)
			(layer "F.Fab")
		)
		(fp_line
			(start 0.67945 0.3048)
			(end 0.120396 0.3048)
			(stroke
				(width 0.1)
				(type default)
			)
			(layer "F.Fab")
		)
		(pad "1" smd circle
			(at -0.40005 0)
			(size 0 0)
			(layers "F.Cu" "F.Mask" "F.Paste")
			(net "SW_P12V_PVCCIN_CPU1_FLT")
		)
		(pad "2" smd circle
			(at 0.40005 0)
			(size 0 0)
			(layers "F.Cu" "F.Mask" "F.Paste")
			(net "GND")
		)
	)
	(footprint ""
		(layer "F.Cu")
		(at 159.951674 -402.371052 -90)
		(property "Reference" "C769"
			(at 0 0 270)
			(layer "F.SilkS")
			(hide yes)
			(effects
				(font
					(size 1.27 1.27)
				)
			)
		)
		(property "Value" ""
			(at 0 0 270)
			(layer "F.Fab")
			(effects
				(font
					(size 1.27 1.27)
				)
			)
		)
		(duplicate_pad_numbers_are_jumpers no)
		(fp_line
			(start -0.299974 0.150114)
			(end -0.299974 -0.150114)
			(stroke
				(width 0.1)
				(type default)
			)
			(layer "F.Fab")
		)
		(fp_line
			(start 0.299974 0.150114)
			(end -0.299974 0.150114)
			(stroke
				(width 0.1)
				(type default)
			)
			(layer "F.Fab")
		)
		(fp_line
			(start -0.299974 -0.150114)
			(end 0.299974 -0.150114)
			(stroke
				(width 0.1)
				(type default)
			)
			(layer "F.Fab")
		)
		(fp_line
			(start 0.299974 -0.150114)
			(end 0.299974 0.150114)
			(stroke
				(width 0.1)
				(type default)
			)
			(layer "F.Fab")
		)
		(pad "1" smd rect
			(at -0.2667 0 270)
			(size 0.3048 0.381)
			(layers "F.Cu" "F.Mask" "F.Paste")
			(net "P5E_CPU1_PE2_TX_C_DP<2>")
		)
		(pad "2" smd rect
			(at 0.2667 0 270)
			(size 0.3048 0.381)
			(layers "F.Cu" "F.Mask" "F.Paste")
			(net "P5E_CPU1_PE2_TX_DP<2>")
		)
	)
)
